(kicad_pcb
	(version 20241229)
	(generator "pcbnew")
	(generator_version "9.0")
	(general
		(thickness 1.62)
		(legacy_teardrops no)
	)
	(paper "A3")
	(title_block
		(title "COM Express 7 Baseboard")
		(date "2025-02-04")
		(rev "1.1.2")
		(company "Antmicro Ltd")
		(comment 1 "www.antmicro.com")
		(comment 9 "footprint 489 of 802 (J12), pads 326-366 of 450")
	)
	(layers
		(0 "F.Cu" signal)
		(4 "In1.Cu" signal)
		(6 "In2.Cu" signal)
		(8 "In3.Cu" signal)
		(10 "In4.Cu" signal)
		(12 "In5.Cu" signal)
		(14 "In6.Cu" signal)
		(2 "B.Cu" signal)
		(9 "F.Adhes" user "F.Adhesive")
		(11 "B.Adhes" user "B.Adhesive")
		(13 "F.Paste" user)
		(15 "B.Paste" user)
		(5 "F.SilkS" user "F.Silkscreen")
		(7 "B.SilkS" user "B.Silkscreen")
		(1 "F.Mask" user)
		(3 "B.Mask" user)
		(17 "Dwgs.User" user "User.Drawings")
		(19 "Cmts.User" user "User.Comments")
		(21 "Eco1.User" user "User.Eco1")
		(23 "Eco2.User" user "User.Eco2")
		(25 "Edge.Cuts" user)
		(27 "Margin" user)
		(31 "F.CrtYd" user "F.Courtyard")
		(29 "B.CrtYd" user "B.Courtyard")
		(35 "F.Fab" user)
		(33 "B.Fab" user)
	)
	(footprint "antmicro-footprints:EPT_401-51501-51"
		(layer "F.Cu")
		(at 203.275 159.81)
		(property "Reference" "J12"
			(at 30.975 -10.45 0)
			(layer "F.SilkS")
			(effects
				(font
					(size 0.7 0.7)
					(thickness 0.15)
				)
				(justify right top)
			)
		)
		(property "Value" "Plug_Bus_CE7_EPT_401-51501-51"
			(at -3.225 52.665 0)
			(layer "F.Fab")
			(hide yes)
			(effects
				(font
					(size 0.7 0.7)
					(thickness 0.15)
				)
				(justify left top)
			)
		)
		(property "Datasheet" "https://www.farnell.com/datasheets/1905093.pdf"
			(at 0 0 0)
			(layer "F.Fab")
			(hide yes)
			(effects
				(font
					(size 1.27 1.27)
					(thickness 0.15)
				)
			)
		)
		(property "Author" "Antmicro"
			(at 406.55 319.62 0)
			(layer "F.Fab")
			(hide yes)
			(effects
				(font
					(size 1 1)
					(thickness 0.15)
				)
			)
		)
		(property "License" "Apache-2.0"
			(at 406.55 319.62 0)
			(layer "F.Fab")
			(hide yes)
			(effects
				(font
					(size 1 1)
					(thickness 0.15)
				)
			)
		)
		(property "MPN" "401-51501-51"
			(at 406.55 319.62 0)
			(layer "F.Fab")
			(hide yes)
			(effects
				(font
					(size 1 1)
					(thickness 0.15)
				)
			)
		)
		(property "Manufacturer" "ept"
			(at 406.55 319.62 0)
			(layer "F.Fab")
			(hide yes)
			(effects
				(font
					(size 1 1)
					(thickness 0.15)
				)
			)
		)
		(sheetname "Com Express 7 Interfaces")
		(sheetfile "com_express_7_interfaces.kicad_sch")
		(attr smd)
		(pad "C101" smd rect
			(at 22.75 -3.125)
			(size 0.3 1.75)
			(layers "F.Cu" "F.Mask" "F.Paste")
			(net 463 "unconnected-(J12N-PCIE_RX31+-PadC101)")
			(pinfunction "PCIE_RX31+")
			(pintype "input+no_connect")
			(teardrops
				(best_length_ratio 0.2)
				(max_length 1)
				(best_width_ratio 0.9)
				(max_width 2)
				(curved_edges yes)
				(filter_ratio 0.9)
				(enabled yes)
				(allow_two_segments yes)
				(prefer_zone_connections yes)
			)
		)
		(pad "C102" smd rect
			(at 23.25 -3.125)
			(size 0.3 1.75)
			(layers "F.Cu" "F.Mask" "F.Paste")
			(net 464 "unconnected-(J12N-PCIE_RX31--PadC102)")
			(pinfunction "PCIE_RX31-")
			(pintype "input+no_connect")
			(teardrops
				(best_length_ratio 0.2)
				(max_length 1)
				(best_width_ratio 0.9)
				(max_width 2)
				(curved_edges yes)
				(filter_ratio 0.9)
				(enabled yes)
				(allow_two_segments yes)
				(prefer_zone_connections yes)
			)
		)
		(pad "C103" smd rect
			(at 23.75 -3.125)
			(size 0.3 1.75)
			(layers "F.Cu" "F.Mask" "F.Paste")
			(net 1 "GND")
			(pinfunction "GND")
			(pintype "power_in")
			(teardrops
				(best_length_ratio 0.2)
				(max_length 1)
				(best_width_ratio 0.9)
				(max_width 2)
				(curved_edges yes)
				(filter_ratio 0.9)
				(enabled yes)
				(allow_two_segments yes)
				(prefer_zone_connections yes)
			)
		)
		(pad "C104" smd rect
			(at 24.25 -3.125)
			(size 0.3 1.75)
			(layers "F.Cu" "F.Mask" "F.Paste")
			(net 65 "+12V")
			(pinfunction "VCC_12V")
			(pintype "power_in")
			(teardrops
				(best_length_ratio 0.2)
				(max_length 1)
				(best_width_ratio 0.9)
				(max_width 2)
				(curved_edges yes)
				(filter_ratio 0.9)
				(enabled yes)
				(allow_two_segments yes)
				(prefer_zone_connections yes)
			)
		)
		(pad "C105" smd rect
			(at 24.75 -3.125)
			(size 0.3 1.75)
			(layers "F.Cu" "F.Mask" "F.Paste")
			(net 65 "+12V")
			(pinfunction "VCC_12V")
			(pintype "passive")
			(teardrops
				(best_length_ratio 0.2)
				(max_length 1)
				(best_width_ratio 0.9)
				(max_width 2)
				(curved_edges yes)
				(filter_ratio 0.9)
				(enabled yes)
				(allow_two_segments yes)
				(prefer_zone_connections yes)
			)
		)
		(pad "C106" smd rect
			(at 25.25 -3.125)
			(size 0.3 1.75)
			(layers "F.Cu" "F.Mask" "F.Paste")
			(net 65 "+12V")
			(pinfunction "VCC_12V")
			(pintype "passive")
			(teardrops
				(best_length_ratio 0.2)
				(max_length 1)
				(best_width_ratio 0.9)
				(max_width 2)
				(curved_edges yes)
				(filter_ratio 0.9)
				(enabled yes)
				(allow_two_segments yes)
				(prefer_zone_connections yes)
			)
		)
		(pad "C107" smd rect
			(at 25.75 -3.125)
			(size 0.3 1.75)
			(layers "F.Cu" "F.Mask" "F.Paste")
			(net 65 "+12V")
			(pinfunction "VCC_12V")
			(pintype "passive")
			(teardrops
				(best_length_ratio 0.2)
				(max_length 1)
				(best_width_ratio 0.9)
				(max_width 2)
				(curved_edges yes)
				(filter_ratio 0.9)
				(enabled yes)
				(allow_two_segments yes)
				(prefer_zone_connections yes)
			)
		)
		(pad "C108" smd rect
			(at 26.25 -3.125)
			(size 0.3 1.75)
			(layers "F.Cu" "F.Mask" "F.Paste")
			(net 65 "+12V")
			(pinfunction "VCC_12V")
			(pintype "passive")
			(teardrops
				(best_length_ratio 0.2)
				(max_length 1)
				(best_width_ratio 0.9)
				(max_width 2)
				(curved_edges yes)
				(filter_ratio 0.9)
				(enabled yes)
				(allow_two_segments yes)
				(prefer_zone_connections yes)
			)
		)
		(pad "C109" smd rect
			(at 26.75 -3.125)
			(size 0.3 1.75)
			(layers "F.Cu" "F.Mask" "F.Paste")
			(net 65 "+12V")
			(pinfunction "VCC_12V")
			(pintype "passive")
			(teardrops
				(best_length_ratio 0.2)
				(max_length 1)
				(best_width_ratio 0.9)
				(max_width 2)
				(curved_edges yes)
				(filter_ratio 0.9)
				(enabled yes)
				(allow_two_segments yes)
				(prefer_zone_connections yes)
			)
		)
		(pad "C110" smd rect
			(at 27.25 -3.125)
			(size 0.3 1.75)
			(layers "F.Cu" "F.Mask" "F.Paste")
			(net 1 "GND")
			(pinfunction "GND(FIXED)")
			(pintype "passive")
			(teardrops
				(best_length_ratio 0.2)
				(max_length 1)
				(best_width_ratio 0.9)
				(max_width 2)
				(curved_edges yes)
				(filter_ratio 0.9)
				(enabled yes)
				(allow_two_segments yes)
				(prefer_zone_connections yes)
			)
		)
		(pad "D1" smd rect
			(at -27.25 -8.675)
			(size 0.3 1.75)
			(layers "F.Cu" "F.Mask" "F.Paste")
			(net 1 "GND")
			(pinfunction "GND(FIXED)")
			(pintype "passive")
			(teardrops
				(best_length_ratio 0.2)
				(max_length 1)
				(best_width_ratio 0.9)
				(max_width 2)
				(curved_edges yes)
				(filter_ratio 0.9)
				(enabled yes)
				(allow_two_segments yes)
				(prefer_zone_connections yes)
			)
		)
		(pad "D2" smd rect
			(at -26.75 -8.675)
			(size 0.3 1.75)
			(layers "F.Cu" "F.Mask" "F.Paste")
			(net 1 "GND")
			(pinfunction "GND")
			(pintype "passive")
			(teardrops
				(best_length_ratio 0.2)
				(max_length 1)
				(best_width_ratio 0.9)
				(max_width 2)
				(curved_edges yes)
				(filter_ratio 0.9)
				(enabled yes)
				(allow_two_segments yes)
				(prefer_zone_connections yes)
			)
		)
		(pad "D3" smd rect
			(at -26.25 -8.675)
			(size 0.3 1.75)
			(layers "F.Cu" "F.Mask" "F.Paste")
			(net 465 "unconnected-(J12J-USB_SSTX0--PadD3)")
			(pinfunction "USB_SSTX0-")
			(pintype "output+no_connect")
			(teardrops
				(best_length_ratio 0.2)
				(max_length 1)
				(best_width_ratio 0.9)
				(max_width 2)
				(curved_edges yes)
				(filter_ratio 0.9)
				(enabled yes)
				(allow_two_segments yes)
				(prefer_zone_connections yes)
			)
		)
		(pad "D4" smd rect
			(at -25.75 -8.675)
			(size 0.3 1.75)
			(layers "F.Cu" "F.Mask" "F.Paste")
			(net 466 "unconnected-(J12J-USB_SSTX0+-PadD4)")
			(pinfunction "USB_SSTX0+")
			(pintype "output+no_connect")
			(teardrops
				(best_length_ratio 0.2)
				(max_length 1)
				(best_width_ratio 0.9)
				(max_width 2)
				(curved_edges yes)
				(filter_ratio 0.9)
				(enabled yes)
				(allow_two_segments yes)
				(prefer_zone_connections yes)
			)
		)
		(pad "D5" smd rect
			(at -25.25 -8.675)
			(size 0.3 1.75)
			(layers "F.Cu" "F.Mask" "F.Paste")
			(net 1 "GND")
			(pinfunction "GND")
			(pintype "passive")
			(teardrops
				(best_length_ratio 0.2)
				(max_length 1)
				(best_width_ratio 0.9)
				(max_width 2)
				(curved_edges yes)
				(filter_ratio 0.9)
				(enabled yes)
				(allow_two_segments yes)
				(prefer_zone_connections yes)
			)
		)
		(pad "D6" smd rect
			(at -24.75 -8.675)
			(size 0.3 1.75)
			(layers "F.Cu" "F.Mask" "F.Paste")
			(net 467 "unconnected-(J12J-USB_SSTX1--PadD6)")
			(pinfunction "USB_SSTX1-")
			(pintype "output+no_connect")
			(teardrops
				(best_length_ratio 0.2)
				(max_length 1)
				(best_width_ratio 0.9)
				(max_width 2)
				(curved_edges yes)
				(filter_ratio 0.9)
				(enabled yes)
				(allow_two_segments yes)
				(prefer_zone_connections yes)
			)
		)
		(pad "D7" smd rect
			(at -24.25 -8.675)
			(size 0.3 1.75)
			(layers "F.Cu" "F.Mask" "F.Paste")
			(net 468 "unconnected-(J12J-USB_SSTX1+-PadD7)")
			(pinfunction "USB_SSTX1+")
			(pintype "output+no_connect")
			(teardrops
				(best_length_ratio 0.2)
				(max_length 1)
				(best_width_ratio 0.9)
				(max_width 2)
				(curved_edges yes)
				(filter_ratio 0.9)
				(enabled yes)
				(allow_two_segments yes)
				(prefer_zone_connections yes)
			)
		)
		(pad "D8" smd rect
			(at -23.75 -8.675)
			(size 0.3 1.75)
			(layers "F.Cu" "F.Mask" "F.Paste")
			(net 1 "GND")
			(pinfunction "GND")
			(pintype "passive")
			(teardrops
				(best_length_ratio 0.2)
				(max_length 1)
				(best_width_ratio 0.9)
				(max_width 2)
				(curved_edges yes)
				(filter_ratio 0.9)
				(enabled yes)
				(allow_two_segments yes)
				(prefer_zone_connections yes)
			)
		)
		(pad "D9" smd rect
			(at -23.25 -8.675)
			(size 0.3 1.75)
			(layers "F.Cu" "F.Mask" "F.Paste")
			(net 47 "/2xUSB3.0+RJ45/USBSS_1.TX-")
			(pinfunction "USB_SSTX2-")
			(pintype "output")
			(teardrops
				(best_length_ratio 0.2)
				(max_length 1)
				(best_width_ratio 0.9)
				(max_width 2)
				(curved_edges yes)
				(filter_ratio 0.9)
				(enabled yes)
				(allow_two_segments yes)
				(prefer_zone_connections yes)
			)
		)
		(pad "D10" smd rect
			(at -22.75 -8.675)
			(size 0.3 1.75)
			(layers "F.Cu" "F.Mask" "F.Paste")
			(net 44 "/2xUSB3.0+RJ45/USBSS_1.TX+")
			(pinfunction "USB_SSTX2+")
			(pintype "output")
			(teardrops
				(best_length_ratio 0.2)
				(max_length 1)
				(best_width_ratio 0.9)
				(max_width 2)
				(curved_edges yes)
				(filter_ratio 0.9)
				(enabled yes)
				(allow_two_segments yes)
				(prefer_zone_connections yes)
			)
		)
		(pad "D11" smd rect
			(at -22.25 -8.675)
			(size 0.3 1.75)
			(layers "F.Cu" "F.Mask" "F.Paste")
			(net 1 "GND")
			(pinfunction "GND(FIXED)")
			(pintype "passive")
			(teardrops
				(best_length_ratio 0.2)
				(max_length 1)
				(best_width_ratio 0.9)
				(max_width 2)
				(curved_edges yes)
				(filter_ratio 0.9)
				(enabled yes)
				(allow_two_segments yes)
				(prefer_zone_connections yes)
			)
		)
		(pad "D12" smd rect
			(at -21.75 -8.675)
			(size 0.3 1.75)
			(layers "F.Cu" "F.Mask" "F.Paste")
			(net 49 "/2xUSB3.0+RJ45/USBSS_2.TX-")
			(pinfunction "USB_SSTX3-")
			(pintype "output")
			(teardrops
				(best_length_ratio 0.2)
				(max_length 1)
				(best_width_ratio 0.9)
				(max_width 2)
				(curved_edges yes)
				(filter_ratio 0.9)
				(enabled yes)
				(allow_two_segments yes)
				(prefer_zone_connections yes)
			)
		)
		(pad "D13" smd rect
			(at -21.25 -8.675)
			(size 0.3 1.75)
			(layers "F.Cu" "F.Mask" "F.Paste")
			(net 45 "/2xUSB3.0+RJ45/USBSS_2.TX+")
			(pinfunction "USB_SSTX3+")
			(pintype "output")
			(teardrops
				(best_length_ratio 0.2)
				(max_length 1)
				(best_width_ratio 0.9)
				(max_width 2)
				(curved_edges yes)
				(filter_ratio 0.9)
				(enabled yes)
				(allow_two_segments yes)
				(prefer_zone_connections yes)
			)
		)
		(pad "D14" smd rect
			(at -20.75 -8.675)
			(size 0.3 1.75)
			(layers "F.Cu" "F.Mask" "F.Paste")
			(net 1 "GND")
			(pinfunction "GND")
			(pintype "passive")
			(teardrops
				(best_length_ratio 0.2)
				(max_length 1)
				(best_width_ratio 0.9)
				(max_width 2)
				(curved_edges yes)
				(filter_ratio 0.9)
				(enabled yes)
				(allow_two_segments yes)
				(prefer_zone_connections yes)
			)
		)
		(pad "D15" smd rect
			(at -20.25 -8.675)
			(size 0.3 1.75)
			(layers "F.Cu" "F.Mask" "F.Paste")
			(net 469 "unconnected-(J12K-10G_PHY_MDIO_SDA3-PadD15)")
			(pinfunction "10G_PHY_MDIO_SDA3")
			(pintype "open_collector+no_connect")
			(teardrops
				(best_length_ratio 0.2)
				(max_length 1)
				(best_width_ratio 0.9)
				(max_width 2)
				(curved_edges yes)
				(filter_ratio 0.9)
				(enabled yes)
				(allow_two_segments yes)
				(prefer_zone_connections yes)
			)
		)
		(pad "D16" smd rect
			(at -19.75 -8.675)
			(size 0.3 1.75)
			(layers "F.Cu" "F.Mask" "F.Paste")
			(net 470 "unconnected-(J12K-10G_PHY_MDIO_SDA2-PadD16)")
			(pinfunction "10G_PHY_MDIO_SDA2")
			(pintype "open_collector+no_connect")
			(teardrops
				(best_length_ratio 0.2)
				(max_length 1)
				(best_width_ratio 0.9)
				(max_width 2)
				(curved_edges yes)
				(filter_ratio 0.9)
				(enabled yes)
				(allow_two_segments yes)
				(prefer_zone_connections yes)
			)
		)
		(pad "D17" smd rect
			(at -19.25 -8.675)
			(size 0.3 1.75)
			(layers "F.Cu" "F.Mask" "F.Paste")
			(net 471 "Net-(J12K-10G_SDP3)")
			(pinfunction "10G_SDP3")
			(pintype "bidirectional")
			(teardrops
				(best_length_ratio 0.2)
				(max_length 1)
				(best_width_ratio 0.9)
				(max_width 2)
				(curved_edges yes)
				(filter_ratio 0.9)
				(enabled yes)
				(allow_two_segments yes)
				(prefer_zone_connections yes)
			)
		)
		(pad "D18" smd rect
			(at -18.75 -8.675)
			(size 0.3 1.75)
			(layers "F.Cu" "F.Mask" "F.Paste")
			(net 1 "GND")
			(pinfunction "GND")
			(pintype "passive")
			(teardrops
				(best_length_ratio 0.2)
				(max_length 1)
				(best_width_ratio 0.9)
				(max_width 2)
				(curved_edges yes)
				(filter_ratio 0.9)
				(enabled yes)
				(allow_two_segments yes)
				(prefer_zone_connections yes)
			)
		)
		(pad "D19" smd rect
			(at -18.25 -8.675)
			(size 0.3 1.75)
			(layers "F.Cu" "F.Mask" "F.Paste")
			(net 472 "unconnected-(J12O-PCIE_TX6+-PadD19)")
			(pinfunction "PCIE_TX6+")
			(pintype "output+no_connect")
			(teardrops
				(best_length_ratio 0.2)
				(max_length 1)
				(best_width_ratio 0.9)
				(max_width 2)
				(curved_edges yes)
				(filter_ratio 0.9)
				(enabled yes)
				(allow_two_segments yes)
				(prefer_zone_connections yes)
			)
		)
		(pad "D20" smd rect
			(at -17.75 -8.675)
			(size 0.3 1.75)
			(layers "F.Cu" "F.Mask" "F.Paste")
			(net 473 "unconnected-(J12O-PCIE_TX6--PadD20)")
			(pinfunction "PCIE_TX6-")
			(pintype "output+no_connect")
			(teardrops
				(best_length_ratio 0.2)
				(max_length 1)
				(best_width_ratio 0.9)
				(max_width 2)
				(curved_edges yes)
				(filter_ratio 0.9)
				(enabled yes)
				(allow_two_segments yes)
				(prefer_zone_connections yes)
			)
		)
		(pad "D21" smd rect
			(at -17.25 -8.675)
			(size 0.3 1.75)
			(layers "F.Cu" "F.Mask" "F.Paste")
			(net 1 "GND")
			(pinfunction "GND(FIXED)")
			(pintype "passive")
			(teardrops
				(best_length_ratio 0.2)
				(max_length 1)
				(best_width_ratio 0.9)
				(max_width 2)
				(curved_edges yes)
				(filter_ratio 0.9)
				(enabled yes)
				(allow_two_segments yes)
				(prefer_zone_connections yes)
			)
		)
		(pad "D22" smd rect
			(at -16.75 -8.675)
			(size 0.3 1.75)
			(layers "F.Cu" "F.Mask" "F.Paste")
			(net 474 "unconnected-(J12O-PCIE_TX7+-PadD22)")
			(pinfunction "PCIE_TX7+")
			(pintype "output+no_connect")
			(teardrops
				(best_length_ratio 0.2)
				(max_length 1)
				(best_width_ratio 0.9)
				(max_width 2)
				(curved_edges yes)
				(filter_ratio 0.9)
				(enabled yes)
				(allow_two_segments yes)
				(prefer_zone_connections yes)
			)
		)
		(pad "D23" smd rect
			(at -16.25 -8.675)
			(size 0.3 1.75)
			(layers "F.Cu" "F.Mask" "F.Paste")
			(net 475 "unconnected-(J12O-PCIE_TX7--PadD23)")
			(pinfunction "PCIE_TX7-")
			(pintype "output+no_connect")
			(teardrops
				(best_length_ratio 0.2)
				(max_length 1)
				(best_width_ratio 0.9)
				(max_width 2)
				(curved_edges yes)
				(filter_ratio 0.9)
				(enabled yes)
				(allow_two_segments yes)
				(prefer_zone_connections yes)
			)
		)
		(pad "D24" smd rect
			(at -15.75 -8.675)
			(size 0.3 1.75)
			(layers "F.Cu" "F.Mask" "F.Paste")
			(net 476 "unconnected-(J12K-10G_INT3-PadD24)")
			(pinfunction "10G_INT3")
			(pintype "input+no_connect")
			(teardrops
				(best_length_ratio 0.2)
				(max_length 1)
				(best_width_ratio 0.9)
				(max_width 2)
				(curved_edges yes)
				(filter_ratio 0.9)
				(enabled yes)
				(allow_two_segments yes)
				(prefer_zone_connections yes)
			)
		)
		(pad "D25" smd rect
			(at -15.25 -8.675)
			(size 0.3 1.75)
			(layers "F.Cu" "F.Mask" "F.Paste")
			(net 1 "GND")
			(pinfunction "GND")
			(pintype "passive")
			(teardrops
				(best_length_ratio 0.2)
				(max_length 1)
				(best_width_ratio 0.9)
				(max_width 2)
				(curved_edges yes)
				(filter_ratio 0.9)
				(enabled yes)
				(allow_two_segments yes)
				(prefer_zone_connections yes)
			)
		)
		(pad "D26" smd rect
			(at -14.75 -8.675)
			(size 0.3 1.75)
			(layers "F.Cu" "F.Mask" "F.Paste")
			(net 477 "unconnected-(J12K-10G_KR_TX3+-PadD26)")
			(pinfunction "10G_KR_TX3+")
			(pintype "output+no_connect")
			(teardrops
				(best_length_ratio 0.2)
				(max_length 1)
				(best_width_ratio 0.9)
				(max_width 2)
				(curved_edges yes)
				(filter_ratio 0.9)
				(enabled yes)
				(allow_two_segments yes)
				(prefer_zone_connections yes)
			)
		)
		(pad "D27" smd rect
			(at -14.25 -8.675)
			(size 0.3 1.75)
			(layers "F.Cu" "F.Mask" "F.Paste")
			(net 478 "unconnected-(J12K-10G_KR_TX3--PadD27)")
			(pinfunction "10G_KR_TX3-")
			(pintype "output+no_connect")
			(teardrops
				(best_length_ratio 0.2)
				(max_length 1)
				(best_width_ratio 0.9)
				(max_width 2)
				(curved_edges yes)
				(filter_ratio 0.9)
				(enabled yes)
				(allow_two_segments yes)
				(prefer_zone_connections yes)
			)
		)
		(pad "D28" smd rect
			(at -13.75 -8.675)
			(size 0.3 1.75)
			(layers "F.Cu" "F.Mask" "F.Paste")
			(net 1 "GND")
			(pinfunction "GND")
			(pintype "passive")
			(teardrops
				(best_length_ratio 0.2)
				(max_length 1)
				(best_width_ratio 0.9)
				(max_width 2)
				(curved_edges yes)
				(filter_ratio 0.9)
				(enabled yes)
				(allow_two_segments yes)
				(prefer_zone_connections yes)
			)
		)
		(pad "D29" smd rect
			(at -13.25 -8.675)
			(size 0.3 1.75)
			(layers "F.Cu" "F.Mask" "F.Paste")
			(net 479 "unconnected-(J12K-10G_KR_TX2+-PadD29)")
			(pinfunction "10G_KR_TX2+")
			(pintype "output+no_connect")
			(teardrops
				(best_length_ratio 0.2)
				(max_length 1)
				(best_width_ratio 0.9)
				(max_width 2)
				(curved_edges yes)
				(filter_ratio 0.9)
				(enabled yes)
				(allow_two_segments yes)
				(prefer_zone_connections yes)
			)
		)
		(pad "D30" smd rect
			(at -12.75 -8.675)
			(size 0.3 1.75)
			(layers "F.Cu" "F.Mask" "F.Paste")
			(net 480 "unconnected-(J12K-10G_KR_TX2--PadD30)")
			(pinfunction "10G_KR_TX2-")
			(pintype "output+no_connect")
			(teardrops
				(best_length_ratio 0.2)
				(max_length 1)
				(best_width_ratio 0.9)
				(max_width 2)
				(curved_edges yes)
				(filter_ratio 0.9)
				(enabled yes)
				(allow_two_segments yes)
				(prefer_zone_connections yes)
			)
		)
		(pad "D31" smd rect
			(at -12.25 -8.675)
			(size 0.3 1.75)
			(layers "F.Cu" "F.Mask" "F.Paste")
			(net 1 "GND")
			(pinfunction "GND(FIXED)")
			(pintype "passive")
			(teardrops
				(best_length_ratio 0.2)
				(max_length 1)
				(best_width_ratio 0.9)
				(max_width 2)
				(curved_edges yes)
				(filter_ratio 0.9)
				(enabled yes)
				(allow_two_segments yes)
				(prefer_zone_connections yes)
			)
		)
	)
)
